# BASEBOARD_FAB2 (Tioga Pass) — schematic netlist excerpt (pin names and nets, part order shuffled) for the footprints in the layout excerpt that follows; sources: Cadence DE-HDL packaged netlist, KiCad conversion of Wiwynn_Tioga_Pass_MB.brd

R3D16  RES  240 1.0% EMPTY  pkg 0402  page 90 : A = PVCCIO_CPU1 ; B = H_CPU1_BMCINIT
C1D23  CAP  1.0UF 16V 10% X6S  pkg 0402  page 208 : A = VR_FET_SW_P12V_STBY_PVCCIN_CPU1 ; B = GND
R9B13  RES  0.0 5% CHIP  pkg 0402  page 113 : A = JTAG_MCP_TMS ; B = JTAG_MCP_TMS_R

(kicad_pcb
	(version 20260206)
	(generator "pcbnew")
	(generator_version "10.0")
	(general
		(thickness 1.6)
		(legacy_teardrops no)
	)
	(paper "A4")
	(title_block
		(title "Wiwynn_Tioga_Pass_MB.brd")
		(comment 1 "Tioga Pass / footprints 302-304 of 4770")
	)
	(layers
		(0 "F.Cu" signal "TOP")
		(4 "In1.Cu" signal "L2GND")
		(6 "In2.Cu" signal "L3")
		(8 "In3.Cu" signal "L4GND")
		(10 "In4.Cu" signal "L5")
		(12 "In5.Cu" signal "L6GND")
		(14 "In6.Cu" signal "L7VCC")
		(16 "In7.Cu" signal "L8VCC")
		(18 "In8.Cu" signal "L9GND")
		(20 "In9.Cu" signal "L10")
		(22 "In10.Cu" signal "L11GND")
		(24 "In11.Cu" signal "L12")
		(26 "In12.Cu" signal "L13GND")
		(2 "B.Cu" signal "BOTTOM")
		(9 "F.Adhes" user "F.Adhesive")
		(11 "B.Adhes" user "B.Adhesive")
		(13 "F.Paste" user "Package Geometry/Pastemask Top")
		(15 "B.Paste" user "Package Geometry/Pastemask Bottom")
		(5 "F.SilkS" user "Ref Des/Silkscreen Top")
		(7 "B.SilkS" user "Ref Des/Silkscreen Bottom")
		(1 "F.Mask" user "Board Geometry/Soldermask Top")
		(3 "B.Mask" user "Board Geometry/Soldermask Bottom")
		(17 "Dwgs.User" user "User.Drawings")
		(19 "Cmts.User" user "User.Comments")
		(21 "Eco1.User" user "User.Eco1")
		(23 "Eco2.User" user "User.Eco2")
		(25 "Edge.Cuts" user "Board Geometry/Outline")
		(27 "Margin" user)
		(31 "F.CrtYd" user "Package Geometry/Place Bound Top")
		(29 "B.CrtYd" user "Package Geometry/Place Bound Bottom")
		(35 "F.Fab" user "Ref Des/Assembly Top")
		(33 "B.Fab" user "Ref Des/Assembly Bottom")
	)
	(footprint ""
		(layer "F.Cu")
		(at 116.3066 -73.025 90)
		(property "Reference" "R3D16"
			(at 0 0 90)
			(layer "F.SilkS")
			(hide yes)
			(effects
				(font
					(size 1.27 1.27)
				)
			)
		)
		(property "Value" ""
			(at 0 0 90)
			(layer "F.Fab")
			(effects
				(font
					(size 1.27 1.27)
				)
			)
		)
		(duplicate_pad_numbers_are_jumpers no)
		(fp_poly
			(pts
				(xy -0.2794 -0.1016) (xy 0.2794 -0.1016) (xy 0.2794 0.9906) (xy -0.2794 0.9906)
			)
			(stroke
				(width 0)
				(type default)
			)
			(fill no)
			(layer "F.CrtYd")
		)
		(fp_line
			(start 0.2794 -0.1016)
			(end -0.2794 -0.1016)
			(stroke
				(width 0.1)
				(type default)
			)
			(layer "F.Fab")
		)
		(fp_line
			(start -0.2794 -0.1016)
			(end -0.2794 0.9906)
			(stroke
				(width 0.1)
				(type default)
			)
			(layer "F.Fab")
		)
		(fp_line
			(start 0.2794 0.9906)
			(end 0.2794 -0.1016)
			(stroke
				(width 0.1)
				(type default)
			)
			(layer "F.Fab")
		)
		(fp_line
			(start -0.2794 0.9906)
			(end 0.2794 0.9906)
			(stroke
				(width 0.1)
				(type default)
			)
			(layer "F.Fab")
		)
		(pad "1" smd rect
			(at 0 0 90)
			(size 0.508 0.508)
			(layers "F.Cu" "F.Mask" "F.Paste")
			(net "PVCCIO_CPU1")
		)
		(pad "2" smd rect
			(at 0 0.889 90)
			(size 0.508 0.508)
			(layers "F.Cu" "F.Mask" "F.Paste")
			(net "H_CPU1_BMCINIT")
		)
		(zone
			(layer "F.Cu")
			(hatch none 0.5)
			(connect_pads
				(clearance 0)
			)
			(min_thickness 0.25)
			(keepout
				(tracks allowed)
				(vias not_allowed)
				(pads allowed)
				(copperpour not_allowed)
				(footprints allowed)
			)
			(placement
				(enabled no)
				(sheetname "")
			)
			(fill
				(thermal_gap 0.5)
				(thermal_bridge_width 0.5)
				(island_removal_mode 0)
			)
			(polygon
				(pts
					(xy 116.5606 -72.771) (xy 116.5606 -73.279) (xy 116.9416 -73.279) (xy 116.9416 -72.771)
				)
			)
		)
		(zone
			(layer "F.Cu")
			(hatch none 0.5)
			(connect_pads
				(clearance 0)
			)
			(min_thickness 0.25)
			(keepout
				(tracks not_allowed)
				(vias allowed)
				(pads allowed)
				(copperpour not_allowed)
				(footprints allowed)
			)
			(placement
				(enabled no)
				(sheetname "")
			)
			(fill
				(thermal_gap 0.5)
				(thermal_bridge_width 0.5)
				(island_removal_mode 0)
			)
			(polygon
				(pts
					(xy 116.9416 -72.771) (xy 116.9416 -73.279) (xy 116.5606 -73.279) (xy 116.5606 -72.771)
				)
			)
		)
	)
	(footprint ""
		(layer "F.Cu")
		(at 29.083 -76.454 -90)
		(property "Reference" "C1D23"
			(at 0 0 270)
			(layer "F.SilkS")
			(hide yes)
			(effects
				(font
					(size 1.27 1.27)
				)
			)
		)
		(property "Value" ""
			(at 0 0 270)
			(layer "F.Fab")
			(effects
				(font
					(size 1.27 1.27)
				)
			)
		)
		(duplicate_pad_numbers_are_jumpers no)
		(fp_rect
			(start 0.3048 -0.1016)
			(end -0.3048 0.9906)
			(stroke
				(width 0)
				(type default)
			)
			(fill no)
			(layer "F.CrtYd")
		)
		(fp_line
			(start -0.3048 0.9906)
			(end 0.3048 0.9906)
			(stroke
				(width 0.1)
				(type default)
			)
			(layer "F.Fab")
		)
		(fp_line
			(start 0.3048 0.9906)
			(end 0.3048 -0.1016)
			(stroke
				(width 0.1)
				(type default)
			)
			(layer "F.Fab")
		)
		(fp_line
			(start -0.3048 -0.1016)
			(end -0.3048 0.9906)
			(stroke
				(width 0.1)
				(type default)
			)
			(layer "F.Fab")
		)
		(fp_line
			(start 0.3048 -0.1016)
			(end -0.3048 -0.1016)
			(stroke
				(width 0.1)
				(type default)
			)
			(layer "F.Fab")
		)
		(pad "1" smd rect
			(at 0 0 270)
			(size 0.508 0.508)
			(layers "F.Cu" "F.Mask" "F.Paste")
			(net "VR_FET_SW_P12V_STBY_PVCCIN_CPU1")
		)
		(pad "2" smd rect
			(at 0 0.889 270)
			(size 0.508 0.508)
			(layers "F.Cu" "F.Mask" "F.Paste")
			(net "GND")
		)
		(zone
			(layer "F.Cu")
			(hatch none 0.5)
			(connect_pads
				(clearance 0)
			)
			(min_thickness 0.25)
			(keepout
				(tracks allowed)
				(vias not_allowed)
				(pads allowed)
				(copperpour not_allowed)
				(footprints allowed)
			)
			(placement
				(enabled no)
				(sheetname "")
			)
			(fill
				(thermal_gap 0.5)
				(thermal_bridge_width 0.5)
				(island_removal_mode 0)
			)
			(polygon
				(pts
					(xy 28.829 -76.2) (xy 28.829 -76.708) (xy 28.448 -76.708) (xy 28.448 -76.2)
				)
			)
		)
		(zone
			(layer "F.Cu")
			(hatch none 0.5)
			(connect_pads
				(clearance 0)
			)
			(min_thickness 0.25)
			(keepout
				(tracks not_allowed)
				(vias allowed)
				(pads allowed)
				(copperpour not_allowed)
				(footprints allowed)
			)
			(placement
				(enabled no)
				(sheetname "")
			)
			(fill
				(thermal_gap 0.5)
				(thermal_bridge_width 0.5)
				(island_removal_mode 0)
			)
			(polygon
				(pts
					(xy 28.829 -76.2) (xy 28.829 -76.708) (xy 28.448 -76.708) (xy 28.448 -76.2)
				)
			)
		)
	)
	(footprint ""
		(layer "F.Cu")
		(at 467.106 -129.413 180)
		(property "Reference" "R9B13"
			(at 0 0 180)
			(layer "F.SilkS")
			(hide yes)
			(effects
				(font
					(size 1.27 1.27)
				)
			)
		)
		(property "Value" ""
			(at 0 0 180)
			(layer "F.Fab")
			(effects
				(font
					(size 1.27 1.27)
				)
			)
		)
		(duplicate_pad_numbers_are_jumpers no)
		(fp_poly
			(pts
				(xy -0.2794 -0.1016) (xy 0.2794 -0.1016) (xy 0.2794 0.9906) (xy -0.2794 0.9906)
			)
			(stroke
				(width 0)
				(type default)
			)
			(fill no)
			(layer "F.CrtYd")
		)
		(fp_line
			(start 0.2794 0.9906)
			(end 0.2794 -0.1016)
			(stroke
				(width 0.1)
				(type default)
			)
			(layer "F.Fab")
		)
		(fp_line
			(start 0.2794 -0.1016)
			(end -0.2794 -0.1016)
			(stroke
				(width 0.1)
				(type default)
			)
			(layer "F.Fab")
		)
		(fp_line
			(start -0.2794 0.9906)
			(end 0.2794 0.9906)
			(stroke
				(width 0.1)
				(type default)
			)
			(layer "F.Fab")
		)
		(fp_line
			(start -0.2794 -0.1016)
			(end -0.2794 0.9906)
			(stroke
				(width 0.1)
				(type default)
			)
			(layer "F.Fab")
		)
		(pad "1" smd rect
			(at 0 0 180)
			(size 0.508 0.508)
			(layers "F.Cu" "F.Mask" "F.Paste")
			(net "JTAG_MCP_TMS")
		)
		(pad "2" smd rect
			(at 0 0.889 180)
			(size 0.508 0.508)
			(layers "F.Cu" "F.Mask" "F.Paste")
			(net "JTAG_MCP_TMS_R")
		)
		(zone
			(layer "F.Cu")
			(hatch none 0.5)
			(connect_pads
				(clearance 0)
			)
			(min_thickness 0.25)
			(keepout
				(tracks not_allowed)
				(vias allowed)
				(pads allowed)
				(copperpour not_allowed)
				(footprints allowed)
			)
			(placement
				(enabled no)
				(sheetname "")
			)
			(fill
				(thermal_gap 0.5)
				(thermal_bridge_width 0.5)
				(island_removal_mode 0)
			)
			(polygon
				(pts
					(xy 467.36 -130.048) (xy 466.852 -130.048) (xy 466.852 -129.667) (xy 467.36 -129.667)
				)
			)
		)
		(zone
			(layer "F.Cu")
			(hatch none 0.5)
			(connect_pads
				(clearance 0)
			)
			(min_thickness 0.25)
			(keepout
				(tracks allowed)
				(vias not_allowed)
				(pads allowed)
				(copperpour not_allowed)
				(footprints allowed)
			)
			(placement
				(enabled no)
				(sheetname "")
			)
			(fill
				(thermal_gap 0.5)
				(thermal_bridge_width 0.5)
				(island_removal_mode 0)
			)
			(polygon
				(pts
					(xy 467.36 -129.667) (xy 466.852 -129.667) (xy 466.852 -130.048) (xy 467.36 -130.048)
				)
			)
		)
	)
)
